(kicad_pcb
	(version 20221018)
	(generator pcbnew)
	(general
    (thickness 1.62)
  )
	(paper "A4")
	(title_block
    (title "ECP5 - Datacenter Secure Control Module (DC-SCM)")
    (date "2024-07-01")
    (rev "1.2.1")
		(comment 9 "footprint 50 of 506 (U21), pads 301-397 of 756")
	)
	(layers
    (0 "F.Cu" signal)
    (1 "In1.Cu" power)
    (2 "In2.Cu" signal)
    (3 "In3.Cu" power)
    (4 "In4.Cu" power)
    (5 "In5.Cu" signal)
    (6 "In6.Cu" power)
    (31 "B.Cu" signal)
    (32 "B.Adhes" user "B.Adhesive")
    (33 "F.Adhes" user "F.Adhesive")
    (34 "B.Paste" user)
    (35 "F.Paste" user)
    (36 "B.SilkS" user "B.Silkscreen")
    (37 "F.SilkS" user "F.Silkscreen")
    (38 "B.Mask" user)
    (39 "F.Mask" user)
    (40 "Dwgs.User" user "User.Drawings")
    (41 "Cmts.User" user "User.Comments")
    (42 "Eco1.User" user "User.Eco1")
    (43 "Eco2.User" user "User.Eco2")
    (44 "Edge.Cuts" user)
    (45 "Margin" user)
    (46 "B.CrtYd" user "B.Courtyard")
    (47 "F.CrtYd" user "F.Courtyard")
    (48 "B.Fab" user)
    (49 "F.Fab" user)
  )
	(footprint "antmicro-footprints:BGA-1024-756_27x27mm_Layout32x32_P0.8mm" locked
    (layer "F.Cu")
    (at 104.4 120.55)
    (property "Author" "Antmicro")
    (property "License" "Apache-2.0")
    (property "MPN" "LFE5UM5G-85F-8BG756C")
    (property "Manufacturer" "Lattice Semiconductor")
    (property "Sheetfile" "fpga-power-supply.kicad_sch")
    (property "Sheetname" "FPGA power supply")
    (property "ki_description" "ECP5-5G Field Programmable Gate Array")
    (property "ki_keywords" "SMT, FPGA, IC")
    (attr smd)
    (fp_text reference "U21" (at -12.97 -14.53) (layer "F.SilkS")
        (effects (font (size 0.7 0.7) (thickness 0.127)))
    )
    (fp_text value "ECP5UM5G_85_CABGA756" (at 0 14.5) (layer "F.Fab")
        (effects (font (size 1 1) (thickness 0.15)))
    )
    (pad "B15" smd circle locked (at -1.2 -11.6) (size 0.4 0.4) (layers "F.Cu" "F.Paste" "F.Mask")
      (net 1 "GND") (pinfunction "GND") (pintype "passive"))
    (pad "B16" smd circle locked (at -0.4 -11.6) (size 0.4 0.4) (layers "F.Cu" "F.Paste" "F.Mask")
      (net 161 "ETH_MDC") (pinfunction "PT60A") (pintype "bidirectional"))
    (pad "B17" smd circle locked (at 0.4 -11.6) (size 0.4 0.4) (layers "F.Cu" "F.Paste" "F.Mask")
      (net 160 "RGMII_REF_CLK") (pinfunction "PT63B") (pintype "bidirectional"))
    (pad "B18" smd circle locked (at 1.2 -11.6) (size 0.4 0.4) (layers "F.Cu" "F.Paste" "F.Mask")
      (net 1 "GND") (pinfunction "GND") (pintype "passive"))
    (pad "B19" smd circle locked (at 2 -11.6) (size 0.4 0.4) (layers "F.Cu" "F.Paste" "F.Mask")
      (net 293 "USR_LED0") (pinfunction "PT76B") (pintype "bidirectional"))
    (pad "B20" smd circle locked (at 2.8 -11.6) (size 0.4 0.4) (layers "F.Cu" "F.Paste" "F.Mask")
      (net 1 "GND") (pinfunction "GND") (pintype "passive"))
    (pad "B22" smd circle locked (at 4.4 -11.6) (size 0.4 0.4) (layers "F.Cu" "F.Paste" "F.Mask")
      (net 47 "I2C[10]_SDA") (pinfunction "PT87B") (pintype "bidirectional"))
    (pad "B23" smd circle locked (at 5.2 -11.6) (size 0.4 0.4) (layers "F.Cu" "F.Paste" "F.Mask")
      (net 48 "I2C[10]_SCL") (pinfunction "PT94B") (pintype "bidirectional"))
    (pad "B24" smd circle locked (at 6 -11.6) (size 0.4 0.4) (layers "F.Cu" "F.Paste" "F.Mask")
      (net 1 "GND") (pinfunction "GND") (pintype "passive"))
    (pad "B25" smd circle locked (at 6.8 -11.6) (size 0.4 0.4) (layers "F.Cu" "F.Paste" "F.Mask")
      (net 51 "I2C[8]_SCL") (pinfunction "PT105B") (pintype "bidirectional"))
    (pad "B26" smd circle locked (at 7.6 -11.6) (size 0.4 0.4) (layers "F.Cu" "F.Paste" "F.Mask")
      (net 52 "I2C[8]_SDA") (pinfunction "PT112B") (pintype "bidirectional"))
    (pad "B28" smd circle locked (at 9.2 -11.6) (size 0.4 0.4) (layers "F.Cu" "F.Paste" "F.Mask")
      (net 1 "GND") (pinfunction "GND") (pintype "passive"))
    (pad "B29" smd circle locked (at 10 -11.6) (size 0.4 0.4) (layers "F.Cu" "F.Paste" "F.Mask")
      (net 33 "I2C[4]_SDA") (pinfunction "PT121A") (pintype "bidirectional"))
    (pad "B30" smd circle locked (at 10.8 -11.6) (size 0.4 0.4) (layers "F.Cu" "F.Paste" "F.Mask")
      (net 23 "I2C[5]_SDA") (pinfunction "PT121B") (pintype "bidirectional"))
    (pad "B31" smd circle locked (at 11.6 -11.6) (size 0.4 0.4) (layers "F.Cu" "F.Paste" "F.Mask")
      (net 1 "GND") (pinfunction "GND") (pintype "passive"))
    (pad "B32" smd circle locked (at 12.4 -11.6) (size 0.4 0.4) (layers "F.Cu" "F.Paste" "F.Mask")
      (net 603 "unconnected-(U21D-PR17A-PadB32)") (pinfunction "PR17A") (pintype "bidirectional+no_connect"))
    (pad "C1" smd circle locked (at -12.4 -10.8) (size 0.4 0.4) (layers "F.Cu" "F.Paste" "F.Mask")
      (net 409 "ROT_RDY\\ROT_GPIO0") (pinfunction "PL20C") (pintype "bidirectional"))
    (pad "C2" smd circle locked (at -11.6 -10.8) (size 0.4 0.4) (layers "F.Cu" "F.Paste" "F.Mask")
      (net 665 "ROT_GPIO2") (pinfunction "PL17B") (pintype "bidirectional"))
    (pad "C3" smd circle locked (at -10.8 -10.8) (size 0.4 0.4) (layers "F.Cu" "F.Paste" "F.Mask")
      (net 604 "unconnected-(U21H-PL11D-PadC3)") (pinfunction "PL11D") (pintype "bidirectional+no_connect"))
    (pad "C4" smd circle locked (at -10 -10.8) (size 0.4 0.4) (layers "F.Cu" "F.Paste" "F.Mask")
      (net 605 "unconnected-(U21H-PL11C-PadC4)") (pinfunction "PL11C") (pintype "bidirectional+no_connect"))
    (pad "C5" smd circle locked (at -9.2 -10.8) (size 0.4 0.4) (layers "F.Cu" "F.Paste" "F.Mask")
      (net 606 "unconnected-(U21H-PL11A-PadC5)") (pinfunction "PL11A") (pintype "bidirectional+no_connect"))
    (pad "C7" smd circle locked (at -7.6 -10.8) (size 0.4 0.4) (layers "F.Cu" "F.Paste" "F.Mask")
      (net 607 "unconnected-(U21B-PT11B-PadC7)") (pinfunction "PT11B") (pintype "bidirectional+no_connect"))
    (pad "C8" smd circle locked (at -6.8 -10.8) (size 0.4 0.4) (layers "F.Cu" "F.Paste" "F.Mask")
      (net 157 "RGMII_RXD3") (pinfunction "PT18B") (pintype "bidirectional"))
    (pad "C9" smd circle locked (at -6 -10.8) (size 0.4 0.4) (layers "F.Cu" "F.Paste" "F.Mask")
      (net 608 "unconnected-(U21B-PT24A-PadC9)") (pinfunction "PT24A") (pintype "bidirectional+no_connect"))
    (pad "C10" smd circle locked (at -5.2 -10.8) (size 0.4 0.4) (layers "F.Cu" "F.Paste" "F.Mask")
      (net 609 "unconnected-(U21B-PT29B-PadC10)") (pinfunction "PT29B") (pintype "bidirectional+no_connect"))
    (pad "C11" smd circle locked (at -4.4 -10.8) (size 0.4 0.4) (layers "F.Cu" "F.Paste" "F.Mask")
      (net 610 "unconnected-(U21B-PT36B-PadC11)") (pinfunction "PT36B") (pintype "bidirectional+no_connect"))
    (pad "C13" smd circle locked (at -2.8 -10.8) (size 0.4 0.4) (layers "F.Cu" "F.Paste" "F.Mask")
      (net 611 "unconnected-(U21B-PT42A-PadC13)") (pinfunction "PT42A") (pintype "bidirectional+no_connect"))
    (pad "C14" smd circle locked (at -2 -10.8) (size 0.4 0.4) (layers "F.Cu" "F.Paste" "F.Mask")
      (net 612 "unconnected-(U21B-PT47B-PadC14)") (pinfunction "PT47B") (pintype "bidirectional+no_connect"))
    (pad "C15" smd circle locked (at -1.2 -10.8) (size 0.4 0.4) (layers "F.Cu" "F.Paste" "F.Mask")
      (net 613 "unconnected-(U21B-PT54A-PadC15)") (pinfunction "PT54A") (pintype "bidirectional+no_connect"))
    (pad "C16" smd circle locked (at -0.4 -10.8) (size 0.4 0.4) (layers "F.Cu" "F.Paste" "F.Mask")
      (net 158 "RGMII_RX_DV") (pinfunction "PT58B") (pintype "bidirectional"))
    (pad "C17" smd circle locked (at 0.4 -10.8) (size 0.4 0.4) (layers "F.Cu" "F.Paste" "F.Mask")
      (net 200 "RGMII_TX_CLK") (pinfunction "PT65A") (pintype "bidirectional"))
    (pad "C18" smd circle locked (at 1.2 -10.8) (size 0.4 0.4) (layers "F.Cu" "F.Paste" "F.Mask")
      (net 614 "unconnected-(U21C-PT71B-PadC18)") (pinfunction "PT71B") (pintype "bidirectional+no_connect"))
    (pad "C19" smd circle locked (at 2 -10.8) (size 0.4 0.4) (layers "F.Cu" "F.Paste" "F.Mask")
      (net 167 "I3C[0]_SDA_3V3") (pinfunction "PT78A") (pintype "bidirectional"))
    (pad "C20" smd circle locked (at 2.8 -10.8) (size 0.4 0.4) (layers "F.Cu" "F.Paste" "F.Mask")
      (net 173 "I3C[3]_SDA_3V3") (pinfunction "PT83B") (pintype "bidirectional"))
    (pad "C22" smd circle locked (at 4.4 -10.8) (size 0.4 0.4) (layers "F.Cu" "F.Paste" "F.Mask")
      (net 294 "USR_LED1") (pinfunction "PT89A") (pintype "bidirectional"))
    (pad "C23" smd circle locked (at 5.2 -10.8) (size 0.4 0.4) (layers "F.Cu" "F.Paste" "F.Mask")
      (net 43 "I2C[9]_SCL") (pinfunction "PT96A") (pintype "bidirectional"))
    (pad "C24" smd circle locked (at 6 -10.8) (size 0.4 0.4) (layers "F.Cu" "F.Paste" "F.Mask")
      (net 44 "I2C[9]_SDA") (pinfunction "PT101B") (pintype "bidirectional"))
    (pad "C25" smd circle locked (at 6.8 -10.8) (size 0.4 0.4) (layers "F.Cu" "F.Paste" "F.Mask")
      (net 30 "I2C[7]_SDA") (pinfunction "PT107A") (pintype "bidirectional"))
    (pad "C26" smd circle locked (at 7.6 -10.8) (size 0.4 0.4) (layers "F.Cu" "F.Paste" "F.Mask")
      (net 36 "I2C[4]_SCL") (pinfunction "PT114A") (pintype "bidirectional"))
    (pad "C28" smd circle locked (at 9.2 -10.8) (size 0.4 0.4) (layers "F.Cu" "F.Paste" "F.Mask")
      (net 615 "unconnected-(U21D-PR11A-PadC28)") (pinfunction "PR11A") (pintype "bidirectional+no_connect"))
    (pad "C29" smd circle locked (at 10 -10.8) (size 0.4 0.4) (layers "F.Cu" "F.Paste" "F.Mask")
      (net 616 "unconnected-(U21D-PR11C-PadC29)") (pinfunction "PR11C") (pintype "bidirectional+no_connect"))
    (pad "C30" smd circle locked (at 10.8 -10.8) (size 0.4 0.4) (layers "F.Cu" "F.Paste" "F.Mask")
      (net 1 "GND") (pinfunction "PR11D") (pintype "bidirectional"))
    (pad "C31" smd circle locked (at 11.6 -10.8) (size 0.4 0.4) (layers "F.Cu" "F.Paste" "F.Mask")
      (net 617 "unconnected-(U21D-PR17B-PadC31)") (pinfunction "PR17B") (pintype "bidirectional+no_connect"))
    (pad "C32" smd circle locked (at 12.4 -10.8) (size 0.4 0.4) (layers "F.Cu" "F.Paste" "F.Mask")
      (net 618 "unconnected-(U21D-PR20C-PadC32)") (pinfunction "PR20C") (pintype "bidirectional+no_connect"))
    (pad "D1" smd circle locked (at -12.4 -10) (size 0.4 0.4) (layers "F.Cu" "F.Paste" "F.Mask")
      (net 659 "ROT_MISO") (pinfunction "PL20D") (pintype "bidirectional"))
    (pad "D2" smd circle locked (at -11.6 -10) (size 0.4 0.4) (layers "F.Cu" "F.Paste" "F.Mask")
      (net 661 "ROT_SS") (pinfunction "PL17D") (pintype "bidirectional"))
    (pad "D3" smd circle locked (at -10.8 -10) (size 0.4 0.4) (layers "F.Cu" "F.Paste" "F.Mask")
      (net 619 "unconnected-(U21H-PL17C-PadD3)") (pinfunction "PL17C") (pintype "bidirectional+no_connect"))
    (pad "D4" smd circle locked (at -10 -10) (size 0.4 0.4) (layers "F.Cu" "F.Paste" "F.Mask")
      (net 620 "unconnected-(U21H-PL14A-PadD4)") (pinfunction "PL14A") (pintype "bidirectional+no_connect"))
    (pad "D5" smd circle locked (at -9.2 -10) (size 0.4 0.4) (layers "F.Cu" "F.Paste" "F.Mask")
      (net 621 "unconnected-(U21H-PL11B-PadD5)") (pinfunction "PL11B") (pintype "bidirectional+no_connect"))
    (pad "D7" smd circle locked (at -7.6 -10) (size 0.4 0.4) (layers "F.Cu" "F.Paste" "F.Mask")
      (net 622 "unconnected-(U21B-PT11A-PadD7)") (pinfunction "PT11A") (pintype "bidirectional+no_connect"))
    (pad "D8" smd circle locked (at -6.8 -10) (size 0.4 0.4) (layers "F.Cu" "F.Paste" "F.Mask")
      (net 201 "RGMII_TXD3") (pinfunction "PT18A") (pintype "bidirectional"))
    (pad "D9" smd circle locked (at -6 -10) (size 0.4 0.4) (layers "F.Cu" "F.Paste" "F.Mask")
      (net 623 "unconnected-(U21B-PT22B-PadD9)") (pinfunction "PT22B") (pintype "bidirectional+no_connect"))
    (pad "D10" smd circle locked (at -5.2 -10) (size 0.4 0.4) (layers "F.Cu" "F.Paste" "F.Mask")
      (net 624 "unconnected-(U21B-PT29A-PadD10)") (pinfunction "PT29A") (pintype "bidirectional+no_connect"))
    (pad "D11" smd circle locked (at -4.4 -10) (size 0.4 0.4) (layers "F.Cu" "F.Paste" "F.Mask")
      (net 625 "unconnected-(U21B-PT36A-PadD11)") (pinfunction "PT36A") (pintype "bidirectional+no_connect"))
    (pad "D13" smd circle locked (at -2.8 -10) (size 0.4 0.4) (layers "F.Cu" "F.Paste" "F.Mask")
      (net 626 "unconnected-(U21B-PT40B-PadD13)") (pinfunction "PT40B") (pintype "bidirectional+no_connect"))
    (pad "D14" smd circle locked (at -2 -10) (size 0.4 0.4) (layers "F.Cu" "F.Paste" "F.Mask")
      (net 627 "unconnected-(U21B-PT47A-PadD14)") (pinfunction "PT47A") (pintype "bidirectional+no_connect"))
    (pad "D15" smd circle locked (at -1.2 -10) (size 0.4 0.4) (layers "F.Cu" "F.Paste" "F.Mask")
      (net 296 "RGMII_TX_EN") (pinfunction "PT51B") (pintype "bidirectional"))
    (pad "D16" smd circle locked (at -0.4 -10) (size 0.4 0.4) (layers "F.Cu" "F.Paste" "F.Mask")
      (net 155 "RGMII_RXD1") (pinfunction "PT58A") (pintype "bidirectional"))
    (pad "D17" smd circle locked (at 0.4 -10) (size 0.4 0.4) (layers "F.Cu" "F.Paste" "F.Mask")
      (net 162 "ETH_MDIO") (pinfunction "PT65B") (pintype "bidirectional"))
    (pad "D18" smd circle locked (at 1.2 -10) (size 0.4 0.4) (layers "F.Cu" "F.Paste" "F.Mask")
      (net 163 "ETH_~{RESET}") (pinfunction "PT74A") (pintype "bidirectional"))
    (pad "D19" smd circle locked (at 2 -10) (size 0.4 0.4) (layers "F.Cu" "F.Paste" "F.Mask")
      (net 169 "I3C[1]_SDA_3V3") (pinfunction "PT78B") (pintype "bidirectional"))
    (pad "D20" smd circle locked (at 2.8 -10) (size 0.4 0.4) (layers "F.Cu" "F.Paste" "F.Mask")
      (net 174 "I3C[3]_SCL_3V3") (pinfunction "PT85A") (pintype "bidirectional"))
    (pad "D22" smd circle locked (at 4.4 -10) (size 0.4 0.4) (layers "F.Cu" "F.Paste" "F.Mask")
      (net 32 "I2C[2]_SCL") (pinfunction "PT89B") (pintype "bidirectional"))
    (pad "D23" smd circle locked (at 5.2 -10) (size 0.4 0.4) (layers "F.Cu" "F.Paste" "F.Mask")
      (net 31 "I2C[2]_SDA") (pinfunction "PT96B") (pintype "bidirectional"))
    (pad "D24" smd circle locked (at 6 -10) (size 0.4 0.4) (layers "F.Cu" "F.Paste" "F.Mask")
      (net 27 "I2C[3]_SDA") (pinfunction "PT103A") (pintype "bidirectional"))
    (pad "D25" smd circle locked (at 6.8 -10) (size 0.4 0.4) (layers "F.Cu" "F.Paste" "F.Mask")
      (net 25 "I2C[3]_SCL") (pinfunction "PT107B") (pintype "bidirectional"))
    (pad "D26" smd circle locked (at 7.6 -10) (size 0.4 0.4) (layers "F.Cu" "F.Paste" "F.Mask")
      (net 38 "I2C[0]_SDA") (pinfunction "PT114B") (pintype "bidirectional"))
    (pad "D28" smd circle locked (at 9.2 -10) (size 0.4 0.4) (layers "F.Cu" "F.Paste" "F.Mask")
      (net 628 "unconnected-(U21D-PR11B-PadD28)") (pinfunction "PR11B") (pintype "bidirectional+no_connect"))
    (pad "D29" smd circle locked (at 10 -10) (size 0.4 0.4) (layers "F.Cu" "F.Paste" "F.Mask")
      (net 629 "unconnected-(U21D-PR14A-PadD29)") (pinfunction "PR14A") (pintype "bidirectional+no_connect"))
    (pad "D30" smd circle locked (at 10.8 -10) (size 0.4 0.4) (layers "F.Cu" "F.Paste" "F.Mask")
      (net 630 "unconnected-(U21D-PR17C-PadD30)") (pinfunction "PR17C") (pintype "bidirectional+no_connect"))
    (pad "D31" smd circle locked (at 11.6 -10) (size 0.4 0.4) (layers "F.Cu" "F.Paste" "F.Mask")
      (net 631 "unconnected-(U21D-PR17D-PadD31)") (pinfunction "PR17D") (pintype "bidirectional+no_connect"))
    (pad "D32" smd circle locked (at 12.4 -10) (size 0.4 0.4) (layers "F.Cu" "F.Paste" "F.Mask")
      (net 632 "unconnected-(U21D-PR20D-PadD32)") (pinfunction "PR20D") (pintype "bidirectional+no_connect"))
    (pad "E1" smd circle locked (at -12.4 -9.2) (size 0.4 0.4) (layers "F.Cu" "F.Paste" "F.Mask")
      (net 664 "ROT_SCLK") (pinfunction "PL23B") (pintype "bidirectional"))
    (pad "E2" smd circle locked (at -11.6 -9.2) (size 0.4 0.4) (layers "F.Cu" "F.Paste" "F.Mask")
      (net 1 "GND") (pinfunction "GND") (pintype "passive"))
    (pad "E3" smd circle locked (at -10.8 -9.2) (size 0.4 0.4) (layers "F.Cu" "F.Paste" "F.Mask")
      (net 660 "ROT_MOSI") (pinfunction "PL20B") (pintype "bidirectional"))
    (pad "E4" smd circle locked (at -10 -9.2) (size 0.4 0.4) (layers "F.Cu" "F.Paste" "F.Mask")
      (net 633 "unconnected-(U21H-PL14B-PadE4)") (pinfunction "PL14B") (pintype "bidirectional+no_connect"))
    (pad "E5" smd circle locked (at -9.2 -9.2) (size 0.4 0.4) (layers "F.Cu" "F.Paste" "F.Mask")
      (net 1 "GND") (pinfunction "GND") (pintype "passive"))
    (pad "E7" smd circle locked (at -7.6 -9.2) (size 0.4 0.4) (layers "F.Cu" "F.Paste" "F.Mask")
      (net 634 "unconnected-(U21A-NC-PadE7)") (pinfunction "NC") (pintype "no_connect"))
    (pad "E8" smd circle locked (at -6.8 -9.2) (size 0.4 0.4) (layers "F.Cu" "F.Paste" "F.Mask")
      (net 635 "unconnected-(U21B-PT15B-PadE8)") (pinfunction "PT15B") (pintype "bidirectional+no_connect"))
    (pad "E9" smd circle locked (at -6 -9.2) (size 0.4 0.4) (layers "F.Cu" "F.Paste" "F.Mask")
      (net 1 "GND") (pinfunction "GND") (pintype "passive"))
    (pad "E10" smd circle locked (at -5.2 -9.2) (size 0.4 0.4) (layers "F.Cu" "F.Paste" "F.Mask")
      (net 636 "unconnected-(U21B-PT27B-PadE10)") (pinfunction "PT27B") (pintype "bidirectional+no_connect"))
    (pad "E11" smd circle locked (at -4.4 -9.2) (size 0.4 0.4) (layers "F.Cu" "F.Paste" "F.Mask")
      (net 637 "unconnected-(U21B-PT33B-PadE11)") (pinfunction "PT33B") (pintype "bidirectional+no_connect"))
    (pad "E13" smd circle locked (at -2.8 -9.2) (size 0.4 0.4) (layers "F.Cu" "F.Paste" "F.Mask")
      (net 1 "GND") (pinfunction "GND") (pintype "passive"))
    (pad "E14" smd circle locked (at -2 -9.2) (size 0.4 0.4) (layers "F.Cu" "F.Paste" "F.Mask")
      (net 638 "unconnected-(U21B-PT45B-PadE14)") (pinfunction "PT45B") (pintype "bidirectional+no_connect"))
    (pad "E15" smd circle locked (at -1.2 -9.2) (size 0.4 0.4) (layers "F.Cu" "F.Paste" "F.Mask")
      (net 1 "GND") (pinfunction "GND") (pintype "passive"))
    (pad "E16" smd circle locked (at -0.4 -9.2) (size 0.4 0.4) (layers "F.Cu" "F.Paste" "F.Mask")
      (net 156 "RGMII_RXD2") (pinfunction "PT56B") (pintype "bidirectional"))
    (pad "E17" smd circle locked (at 0.4 -9.2) (size 0.4 0.4) (layers "F.Cu" "F.Paste" "F.Mask")
      (net 639 "unconnected-(U21C-PT69A-PadE17)") (pinfunction "PT69A") (pintype "bidirectional+no_connect"))
    (pad "E18" smd circle locked (at 1.2 -9.2) (size 0.4 0.4) (layers "F.Cu" "F.Paste" "F.Mask")
      (net 1 "GND") (pinfunction "GND") (pintype "passive"))
    (pad "E19" smd circle locked (at 2 -9.2) (size 0.4 0.4) (layers "F.Cu" "F.Paste" "F.Mask")
      (net 172 "I3C[2]_SCL_3V3") (pinfunction "PT80A") (pintype "bidirectional"))
    (pad "E20" smd circle locked (at 2.8 -9.2) (size 0.4 0.4) (layers "F.Cu" "F.Paste" "F.Mask")
      (net 1 "GND") (pinfunction "GND") (pintype "passive"))
    (pad "E22" smd circle locked (at 4.4 -9.2) (size 0.4 0.4) (layers "F.Cu" "F.Paste" "F.Mask")
      (net 28 "I2C[1]_SCL") (pinfunction "PT92A") (pintype "bidirectional"))
    (pad "E23" smd circle locked (at 5.2 -9.2) (size 0.4 0.4) (layers "F.Cu" "F.Paste" "F.Mask")
      (net 29 "I2C[1]_SDA") (pinfunction "PT98A") (pintype "bidirectional"))
    (pad "E24" smd circle locked (at 6 -9.2) (size 0.4 0.4) (layers "F.Cu" "F.Paste" "F.Mask")
      (net 1 "GND") (pinfunction "GND") (pintype "passive"))
    (pad "E25" smd circle locked (at 6.8 -9.2) (size 0.4 0.4) (layers "F.Cu" "F.Paste" "F.Mask")
      (net 37 "I2C[0]_SCL") (pinfunction "PT110A") (pintype "bidirectional"))
    (pad "E26" smd circle locked (at 7.6 -9.2) (size 0.4 0.4) (layers "F.Cu" "F.Paste" "F.Mask")
      (net 640 "unconnected-(U21A-NC-PadE26)") (pinfunction "NC") (pintype "no_connect"))
    (pad "E28" smd circle locked (at 9.2 -9.2) (size 0.4 0.4) (layers "F.Cu" "F.Paste" "F.Mask")
      (net 1 "GND") (pinfunction "GND") (pintype "passive"))
    (pad "E29" smd circle locked (at 10 -9.2) (size 0.4 0.4) (layers "F.Cu" "F.Paste" "F.Mask")
      (net 641 "unconnected-(U21D-PR14B-PadE29)") (pinfunction "PR14B") (pintype "bidirectional+no_connect"))
  )
)
